(kicad_pcb
	(version 20260206)
	(generator "pcbnew")
	(generator_version "10.0")
	(general
		(thickness 1.6)
		(legacy_teardrops no)
	)
	(paper "A4")
	(title_block
		(title "timecard-production-celestica-r4006 — R4006-B0001-02_R01.brd")
		(comment 1 "Time Appliance Project (Time Card) / footprints 794-798 of 1113")
	)
	(layers
		(0 "F.Cu" signal "TOP")
		(4 "In1.Cu" signal "L02_GND1")
		(6 "In2.Cu" signal "L03_SIG1")
		(8 "In3.Cu" signal "L04_GND2")
		(10 "In4.Cu" signal "L05_VCC1")
		(12 "In5.Cu" signal "L06_VCC2")
		(14 "In6.Cu" signal "L07_GND3")
		(16 "In7.Cu" signal "L08_SIG2")
		(18 "In8.Cu" signal "L09_GND4")
		(2 "B.Cu" signal "BOTTOM")
		(9 "F.Adhes" user "F.Adhesive")
		(11 "B.Adhes" user "B.Adhesive")
		(13 "F.Paste" user "Package Geometry/Pastemask Top")
		(15 "B.Paste" user "Package Geometry/Pastemask Bottom")
		(5 "F.SilkS" user "Ref Des/Silkscreen Top")
		(7 "B.SilkS" user "Ref Des/Silkscreen Bottom")
		(1 "F.Mask" user "Board Geometry/Soldermask Top")
		(3 "B.Mask" user "Board Geometry/Soldermask Bottom")
		(17 "Dwgs.User" user "User.Drawings")
		(19 "Cmts.User" user "User.Comments")
		(21 "Eco1.User" user "User.Eco1")
		(23 "Eco2.User" user "User.Eco2")
		(25 "Edge.Cuts" user "Board Geometry/Outline")
		(27 "Margin" user)
		(31 "F.CrtYd" user "Package Geometry/Place Bound Top")
		(29 "B.CrtYd" user "Package Geometry/Place Bound Bottom")
		(35 "F.Fab" user "Ref Des/Assembly Top")
		(33 "B.Fab" user "Ref Des/Assembly Bottom")
	)
	(footprint ""
		(layer "B.Cu")
		(at 111.125 -98.171)
		(property "Reference" "R319"
			(at 0.254 1.81737 0)
			(unlocked yes)
			(layer "B.SilkS")
			(effects
				(font
					(size 0.7874 0.5842)
					(thickness 0.1524)
				)
				(justify mirror)
			)
		)
		(property "Value" "VAL*"
			(at -0.02032 2.13233 0)
			(unlocked yes)
			(layer "B.Fab")
			(hide yes)
			(effects
				(font
					(size 0.7874 0.5842)
					(thickness 0.1524)
				)
				(justify mirror)
			)
		)
		(property "Tolerance" "TOL*"
			(at -0.044704 3.05435 0)
			(unlocked yes)
			(layer "Cmts.User")
			(hide yes)
			(effects
				(font
					(size 0.7874 0.5842)
					(thickness 0.1524)
				)
				(justify mirror)
			)
		)
		(property "User Part Number" "PARTNUM*"
			(at -0.02032 4.024884 0)
			(unlocked yes)
			(layer "Cmts.User")
			(hide yes)
			(effects
				(font
					(size 0.7874 0.5842)
					(thickness 0.1524)
				)
				(justify mirror)
			)
		)
		(property "Device Type" "RESISTOR-G155-133R0-01,33OHM,1%"
			(at -0.008382 1.210564 0)
			(unlocked yes)
			(layer "B.Fab")
			(hide yes)
			(effects
				(font
					(size 0.7874 0.5842)
					(thickness 0.1524)
				)
				(justify mirror)
			)
		)
		(duplicate_pad_numbers_are_jumpers no)
		(fp_line
			(start -1.143 -0.5588)
			(end 1.143 -0.5588)
			(stroke
				(width 0.1)
				(type default)
			)
			(layer "B.SilkS")
		)
		(fp_line
			(start -1.143 0.5588)
			(end -1.143 -0.5588)
			(stroke
				(width 0.1)
				(type default)
			)
			(layer "B.SilkS")
		)
		(fp_line
			(start 1.143 -0.5588)
			(end 1.143 0.5588)
			(stroke
				(width 0.1)
				(type default)
			)
			(layer "B.SilkS")
		)
		(fp_line
			(start 1.143 0.5588)
			(end -1.143 0.5588)
			(stroke
				(width 0.1)
				(type default)
			)
			(layer "B.SilkS")
		)
		(fp_poly
			(pts
				(xy 1.143 0.5588) (xy -1.143 0.5588) (xy -1.143 -0.5588) (xy 1.143 -0.5588)
			)
			(stroke
				(width 0)
				(type default)
			)
			(fill no)
			(layer "B.CrtYd")
		)
		(fp_line
			(start -0.508 -0.3048)
			(end 0.508 -0.3048)
			(stroke
				(width 0.1)
				(type default)
			)
			(layer "B.Fab")
		)
		(fp_line
			(start -0.508 0.3048)
			(end -0.508 -0.3048)
			(stroke
				(width 0.1)
				(type default)
			)
			(layer "B.Fab")
		)
		(fp_line
			(start 0.508 -0.3048)
			(end 0.508 0.3048)
			(stroke
				(width 0.1)
				(type default)
			)
			(layer "B.Fab")
		)
		(fp_line
			(start 0.508 0.3048)
			(end -0.508 0.3048)
			(stroke
				(width 0.1)
				(type default)
			)
			(layer "B.Fab")
		)
		(pad "1" smd rect
			(at 0.5334 0 180)
			(size 0.7112 0.6096)
			(layers "B.Cu" "B.Mask" "B.Paste")
			(net "FPGA_OUT_RGB_LED_SHUTDOWN_N")
		)
		(pad "2" smd rect
			(at -0.5334 0 180)
			(size 0.7112 0.6096)
			(layers "B.Cu" "B.Mask" "B.Paste")
			(net "RGB_LED_SHUTDOWN_N")
		)
		(zone
			(layer "B.Cu")
			(hatch none 0.5)
			(connect_pads
				(clearance 0)
			)
			(min_thickness 0.25)
			(keepout
				(tracks allowed)
				(vias not_allowed)
				(pads allowed)
				(copperpour not_allowed)
				(footprints allowed)
			)
			(placement
				(enabled no)
				(sheetname "")
			)
			(fill
				(thermal_gap 0.5)
				(thermal_bridge_width 0.5)
				(island_removal_mode 0)
			)
			(polygon
				(pts
					(xy 111.2012 -97.8662) (xy 111.2012 -98.4758) (xy 111.0488 -98.4758) (xy 111.0488 -97.8662)
				)
			)
		)
		(zone
			(layer "B.Cu")
			(hatch none 0.5)
			(connect_pads
				(clearance 0)
			)
			(min_thickness 0.25)
			(keepout
				(tracks not_allowed)
				(vias allowed)
				(pads allowed)
				(copperpour not_allowed)
				(footprints allowed)
			)
			(placement
				(enabled no)
				(sheetname "")
			)
			(fill
				(thermal_gap 0.5)
				(thermal_bridge_width 0.5)
				(island_removal_mode 0)
			)
			(polygon
				(pts
					(xy 111.2012 -97.8662) (xy 111.2012 -98.4758) (xy 111.0488 -98.4758) (xy 111.0488 -97.8662)
				)
			)
		)
	)
	(footprint ""
		(layer "B.Cu")
		(at 53.467 -87.122 90)
		(property "Reference" "R454"
			(at 5.16763 0.635 0)
			(unlocked yes)
			(layer "B.SilkS")
			(effects
				(font
					(size 0.7874 0.5842)
					(thickness 0.1524)
				)
				(justify mirror)
			)
		)
		(property "Value" "VAL*"
			(at -0.0508 2.245106 90)
			(unlocked yes)
			(layer "B.Fab")
			(hide yes)
			(effects
				(font
					(size 0.7874 0.5842)
					(thickness 0.1524)
				)
				(justify mirror)
			)
		)
		(property "User Part Number" "PARTNUM*"
			(at -0.0762 4.302506 90)
			(unlocked yes)
			(layer "Cmts.User")
			(hide yes)
			(effects
				(font
					(size 0.7874 0.5842)
					(thickness 0.1524)
				)
				(justify mirror)
			)
		)
		(property "Device Type" "RESISTOR-G155-02101-01,2.1KOHMA"
			(at -0.0762 1.254506 90)
			(unlocked yes)
			(layer "B.Fab")
			(hide yes)
			(effects
				(font
					(size 0.7874 0.5842)
					(thickness 0.1524)
				)
				(justify mirror)
			)
		)
		(property "Tolerance" "TOL*"
			(at -0.0508 3.261106 90)
			(unlocked yes)
			(layer "Cmts.User")
			(hide yes)
			(effects
				(font
					(size 0.7874 0.5842)
					(thickness 0.1524)
				)
				(justify mirror)
			)
		)
		(duplicate_pad_numbers_are_jumpers no)
		(fp_line
			(start 1.143 -0.5588)
			(end 1.143 0.5588)
			(stroke
				(width 0.1)
				(type default)
			)
			(layer "B.SilkS")
		)
		(fp_line
			(start -1.143 -0.5588)
			(end 1.143 -0.5588)
			(stroke
				(width 0.1)
				(type default)
			)
			(layer "B.SilkS")
		)
		(fp_line
			(start 1.143 0.5588)
			(end -1.143 0.5588)
			(stroke
				(width 0.1)
				(type default)
			)
			(layer "B.SilkS")
		)
		(fp_line
			(start -1.143 0.5588)
			(end -1.143 -0.5588)
			(stroke
				(width 0.1)
				(type default)
			)
			(layer "B.SilkS")
		)
		(fp_poly
			(pts
				(xy 1.143 0.5588) (xy -1.143 0.5588) (xy -1.143 -0.5588) (xy 1.143 -0.5588)
			)
			(stroke
				(width 0)
				(type default)
			)
			(fill no)
			(layer "B.CrtYd")
		)
		(fp_line
			(start 0.508 -0.3048)
			(end 0.508 0.3048)
			(stroke
				(width 0.1)
				(type default)
			)
			(layer "B.Fab")
		)
		(fp_line
			(start -0.508 -0.3048)
			(end 0.508 -0.3048)
			(stroke
				(width 0.1)
				(type default)
			)
			(layer "B.Fab")
		)
		(fp_line
			(start 0.508 0.3048)
			(end -0.508 0.3048)
			(stroke
				(width 0.1)
				(type default)
			)
			(layer "B.Fab")
		)
		(fp_line
			(start -0.508 0.3048)
			(end -0.508 -0.3048)
			(stroke
				(width 0.1)
				(type default)
			)
			(layer "B.Fab")
		)
		(pad "1" smd rect
			(at 0.5334 0 270)
			(size 0.7112 0.6096)
			(layers "B.Cu" "B.Mask" "B.Paste")
			(net "FTDI_EE_DAT")
		)
		(pad "2" smd rect
			(at -0.5334 0 270)
			(size 0.7112 0.6096)
			(layers "B.Cu" "B.Mask" "B.Paste")
			(net "FTDI_EE_DO")
		)
		(zone
			(layer "B.Cu")
			(hatch none 0.5)
			(connect_pads
				(clearance 0)
			)
			(min_thickness 0.25)
			(keepout
				(tracks allowed)
				(vias not_allowed)
				(pads allowed)
				(copperpour not_allowed)
				(footprints allowed)
			)
			(placement
				(enabled no)
				(sheetname "")
			)
			(fill
				(thermal_gap 0.5)
				(thermal_bridge_width 0.5)
				(island_removal_mode 0)
			)
			(polygon
				(pts
					(xy 53.7718 -87.1982) (xy 53.1622 -87.1982) (xy 53.1622 -87.0458) (xy 53.7718 -87.0458)
				)
			)
		)
		(zone
			(layer "B.Cu")
			(hatch none 0.5)
			(connect_pads
				(clearance 0)
			)
			(min_thickness 0.25)
			(keepout
				(tracks not_allowed)
				(vias allowed)
				(pads allowed)
				(copperpour not_allowed)
				(footprints allowed)
			)
			(placement
				(enabled no)
				(sheetname "")
			)
			(fill
				(thermal_gap 0.5)
				(thermal_bridge_width 0.5)
				(island_removal_mode 0)
			)
			(polygon
				(pts
					(xy 53.7718 -87.1982) (xy 53.1622 -87.1982) (xy 53.1622 -87.0458) (xy 53.7718 -87.0458)
				)
			)
		)
	)
	(footprint ""
		(layer "B.Cu")
		(at 52.9082 -74.9808 90)
		(property "Reference" "R409"
			(at 4.064 0.08763 270)
			(unlocked yes)
			(layer "B.SilkS")
			(effects
				(font
					(size 0.7874 0.5842)
					(thickness 0.1524)
				)
				(justify mirror)
			)
		)
		(property "Value" "VAL*"
			(at -0.02032 2.13233 90)
			(unlocked yes)
			(layer "B.Fab")
			(hide yes)
			(effects
				(font
					(size 0.7874 0.5842)
					(thickness 0.1524)
				)
				(justify mirror)
			)
		)
		(property "Device Type" "RESISTOR-G155-11001-01,1KOHM,1%"
			(at -0.008382 1.210564 90)
			(unlocked yes)
			(layer "B.Fab")
			(hide yes)
			(effects
				(font
					(size 0.7874 0.5842)
					(thickness 0.1524)
				)
				(justify mirror)
			)
		)
		(property "User Part Number" "PARTNUM*"
			(at -0.02032 4.024884 90)
			(unlocked yes)
			(layer "Cmts.User")
			(hide yes)
			(effects
				(font
					(size 0.7874 0.5842)
					(thickness 0.1524)
				)
				(justify mirror)
			)
		)
		(property "Tolerance" "TOL*"
			(at -0.044704 3.05435 90)
			(unlocked yes)
			(layer "Cmts.User")
			(hide yes)
			(effects
				(font
					(size 0.7874 0.5842)
					(thickness 0.1524)
				)
				(justify mirror)
			)
		)
		(duplicate_pad_numbers_are_jumpers no)
		(fp_line
			(start 1.143 -0.5588)
			(end 1.143 0.5588)
			(stroke
				(width 0.1)
				(type default)
			)
			(layer "B.SilkS")
		)
		(fp_line
			(start -1.143 -0.5588)
			(end 1.143 -0.5588)
			(stroke
				(width 0.1)
				(type default)
			)
			(layer "B.SilkS")
		)
		(fp_line
			(start 1.143 0.5588)
			(end -1.143 0.5588)
			(stroke
				(width 0.1)
				(type default)
			)
			(layer "B.SilkS")
		)
		(fp_line
			(start -1.143 0.5588)
			(end -1.143 -0.5588)
			(stroke
				(width 0.1)
				(type default)
			)
			(layer "B.SilkS")
		)
		(fp_rect
			(start 1.143 0.5588)
			(end -1.143 -0.5588)
			(stroke
				(width 0)
				(type default)
			)
			(fill no)
			(layer "B.CrtYd")
		)
		(fp_line
			(start 0.508 -0.3048)
			(end 0.508 0.3048)
			(stroke
				(width 0.1)
				(type default)
			)
			(layer "B.Fab")
		)
		(fp_line
			(start -0.508 -0.3048)
			(end 0.508 -0.3048)
			(stroke
				(width 0.1)
				(type default)
			)
			(layer "B.Fab")
		)
		(fp_line
			(start 0.508 0.3048)
			(end -0.508 0.3048)
			(stroke
				(width 0.1)
				(type default)
			)
			(layer "B.Fab")
		)
		(fp_line
			(start -0.508 0.3048)
			(end -0.508 -0.3048)
			(stroke
				(width 0.1)
				(type default)
			)
			(layer "B.Fab")
		)
		(pad "1" smd rect
			(at 0.5334 0 270)
			(size 0.7112 0.6096)
			(layers "B.Cu" "B.Mask" "B.Paste")
			(net "UNNAMED_6_LM75BDPTSSOP8_I59_A2")
		)
		(pad "2" smd rect
			(at -0.5334 0 270)
			(size 0.7112 0.6096)
			(layers "B.Cu" "B.Mask" "B.Paste")
			(net "SG")
		)
		(zone
			(layer "B.Cu")
			(hatch none 0.5)
			(connect_pads
				(clearance 0)
			)
			(min_thickness 0.25)
			(keepout
				(tracks allowed)
				(vias not_allowed)
				(pads allowed)
				(copperpour not_allowed)
				(footprints allowed)
			)
			(placement
				(enabled no)
				(sheetname "")
			)
			(fill
				(thermal_gap 0.5)
				(thermal_bridge_width 0.5)
				(island_removal_mode 0)
			)
			(polygon
				(pts
					(xy 53.213 -75.057) (xy 52.6034 -75.057) (xy 52.6034 -74.9046) (xy 53.213 -74.9046)
				)
			)
		)
		(zone
			(layer "B.Cu")
			(hatch none 0.5)
			(connect_pads
				(clearance 0)
			)
			(min_thickness 0.25)
			(keepout
				(tracks not_allowed)
				(vias allowed)
				(pads allowed)
				(copperpour not_allowed)
				(footprints allowed)
			)
			(placement
				(enabled no)
				(sheetname "")
			)
			(fill
				(thermal_gap 0.5)
				(thermal_bridge_width 0.5)
				(island_removal_mode 0)
			)
			(polygon
				(pts
					(xy 53.213 -75.057) (xy 52.6034 -75.057) (xy 52.6034 -74.9046) (xy 53.213 -74.9046)
				)
			)
		)
	)
	(footprint ""
		(layer "B.Cu")
		(at 80.899 -96.266 90)
		(property "Reference" "R39"
			(at -0.127 -1.69037 270)
			(unlocked yes)
			(layer "B.SilkS")
			(effects
				(font
					(size 0.7874 0.5842)
					(thickness 0.1524)
				)
				(justify mirror)
			)
		)
		(property "Value" "VAL*"
			(at -0.0508 3.159506 90)
			(unlocked yes)
			(layer "B.Fab")
			(hide yes)
			(effects
				(font
					(size 0.7874 0.5842)
					(thickness 0.1524)
				)
				(justify mirror)
			)
		)
		(property "Device Type" "RESISTOR-G157-12R20-01,2.2OHM,A"
			(at 0 2.194306 90)
			(unlocked yes)
			(layer "B.Fab")
			(hide yes)
			(effects
				(font
					(size 0.7874 0.5842)
					(thickness 0.1524)
				)
				(justify mirror)
			)
		)
		(property "User Part Number" "PARTNUM*"
			(at -0.0508 5.089906 90)
			(unlocked yes)
			(layer "Cmts.User")
			(hide yes)
			(effects
				(font
					(size 0.7874 0.5842)
					(thickness 0.1524)
				)
				(justify mirror)
			)
		)
		(property "Tolerance" "TOL*"
			(at -0.0508 4.124706 90)
			(unlocked yes)
			(layer "Cmts.User")
			(hide yes)
			(effects
				(font
					(size 0.7874 0.5842)
					(thickness 0.1524)
				)
				(justify mirror)
			)
		)
		(duplicate_pad_numbers_are_jumpers no)
		(fp_line
			(start 1.5748 -0.9398)
			(end 1.5748 0.9398)
			(stroke
				(width 0.1)
				(type default)
			)
			(layer "B.SilkS")
		)
		(fp_line
			(start -1.5748 -0.9398)
			(end 1.5748 -0.9398)
			(stroke
				(width 0.1)
				(type default)
			)
			(layer "B.SilkS")
		)
		(fp_line
			(start 1.5748 0.9398)
			(end -1.5748 0.9398)
			(stroke
				(width 0.1)
				(type default)
			)
			(layer "B.SilkS")
		)
		(fp_line
			(start -1.5748 0.9398)
			(end -1.5748 -0.9398)
			(stroke
				(width 0.1)
				(type default)
			)
			(layer "B.SilkS")
		)
		(fp_rect
			(start -1.5748 0.9398)
			(end 1.5748 -0.9398)
			(stroke
				(width 0)
				(type default)
			)
			(fill no)
			(layer "B.CrtYd")
		)
		(fp_line
			(start 1.016 -0.635)
			(end 1.016 0.635)
			(stroke
				(width 0.1)
				(type default)
			)
			(layer "B.Fab")
		)
		(fp_line
			(start -1.016 -0.635)
			(end 1.016 -0.635)
			(stroke
				(width 0.1)
				(type default)
			)
			(layer "B.Fab")
		)
		(fp_line
			(start 1.016 0.635)
			(end -1.016 0.635)
			(stroke
				(width 0.1)
				(type default)
			)
			(layer "B.Fab")
		)
		(fp_line
			(start -1.016 0.635)
			(end -1.016 -0.635)
			(stroke
				(width 0.1)
				(type default)
			)
			(layer "B.Fab")
		)
		(pad "1" smd rect
			(at 0.8382 0 270)
			(size 0.9652 1.3716)
			(layers "B.Cu" "B.Mask" "B.Paste")
			(net "UNNAMED_517_CAPACITOR_I29_2")
		)
		(pad "2" smd rect
			(at -0.8382 0 270)
			(size 0.9652 1.3716)
			(layers "B.Cu" "B.Mask" "B.Paste")
			(net "SG")
		)
		(zone
			(layer "B.Cu")
			(hatch none 0.5)
			(connect_pads
				(clearance 0)
			)
			(min_thickness 0.25)
			(keepout
				(tracks allowed)
				(vias not_allowed)
				(pads allowed)
				(copperpour not_allowed)
				(footprints allowed)
			)
			(placement
				(enabled no)
				(sheetname "")
			)
			(fill
				(thermal_gap 0.5)
				(thermal_bridge_width 0.5)
				(island_removal_mode 0)
			)
			(polygon
				(pts
					(xy 81.534 -96.0374) (xy 81.534 -96.4946) (xy 80.264 -96.4946) (xy 80.264 -96.0374)
				)
			)
		)
	)
	(footprint ""
		(layer "B.Cu")
		(at 85.09 -73.279 -90)
		(property "Reference" "R363"
			(at 3.556 0.03937 270)
			(unlocked yes)
			(layer "B.SilkS")
			(effects
				(font
					(size 0.7874 0.5842)
					(thickness 0.1524)
				)
				(justify mirror)
			)
		)
		(property "Value" "VAL*"
			(at -0.02032 2.13233 270)
			(unlocked yes)
			(layer "B.Fab")
			(hide yes)
			(effects
				(font
					(size 0.7874 0.5842)
					(thickness 0.1524)
				)
				(justify mirror)
			)
		)
		(property "Tolerance" "TOL*"
			(at -0.044704 3.05435 270)
			(unlocked yes)
			(layer "Cmts.User")
			(hide yes)
			(effects
				(font
					(size 0.7874 0.5842)
					(thickness 0.1524)
				)
				(justify mirror)
			)
		)
		(property "User Part Number" "PARTNUM*"
			(at -0.02032 4.024884 270)
			(unlocked yes)
			(layer "Cmts.User")
			(hide yes)
			(effects
				(font
					(size 0.7874 0.5842)
					(thickness 0.1524)
				)
				(justify mirror)
			)
		)
		(property "Device Type" "RESISTOR-G155-133R0-01,33OHM,1%"
			(at -0.008382 1.210564 270)
			(unlocked yes)
			(layer "B.Fab")
			(hide yes)
			(effects
				(font
					(size 0.7874 0.5842)
					(thickness 0.1524)
				)
				(justify mirror)
			)
		)
		(duplicate_pad_numbers_are_jumpers no)
		(fp_line
			(start -1.143 0.5588)
			(end -1.143 -0.5588)
			(stroke
				(width 0.1)
				(type default)
			)
			(layer "B.SilkS")
		)
		(fp_line
			(start 1.143 0.5588)
			(end -1.143 0.5588)
			(stroke
				(width 0.1)
				(type default)
			)
			(layer "B.SilkS")
		)
		(fp_line
			(start -1.143 -0.5588)
			(end 1.143 -0.5588)
			(stroke
				(width 0.1)
				(type default)
			)
			(layer "B.SilkS")
		)
		(fp_line
			(start 1.143 -0.5588)
			(end 1.143 0.5588)
			(stroke
				(width 0.1)
				(type default)
			)
			(layer "B.SilkS")
		)
		(fp_rect
			(start 1.143 0.5588)
			(end -1.143 -0.5588)
			(stroke
				(width 0)
				(type default)
			)
			(fill no)
			(layer "B.CrtYd")
		)
		(fp_line
			(start -0.508 0.3048)
			(end -0.508 -0.3048)
			(stroke
				(width 0.1)
				(type default)
			)
			(layer "B.Fab")
		)
		(fp_line
			(start 0.508 0.3048)
			(end -0.508 0.3048)
			(stroke
				(width 0.1)
				(type default)
			)
			(layer "B.Fab")
		)
		(fp_line
			(start -0.508 -0.3048)
			(end 0.508 -0.3048)
			(stroke
				(width 0.1)
				(type default)
			)
			(layer "B.Fab")
		)
		(fp_line
			(start 0.508 -0.3048)
			(end 0.508 0.3048)
			(stroke
				(width 0.1)
				(type default)
			)
			(layer "B.Fab")
		)
		(pad "1" smd rect
			(at 0.5334 0 90)
			(size 0.7112 0.6096)
			(layers "B.Cu" "B.Mask" "B.Paste")
			(net "R_BNO080_EVN_SCL")
		)
		(pad "2" smd rect
			(at -0.5334 0 90)
			(size 0.7112 0.6096)
			(layers "B.Cu" "B.Mask" "B.Paste")
			(net "BNO080_EVN_SCL")
		)
		(zone
			(layer "B.Cu")
			(hatch none 0.5)
			(connect_pads
				(clearance 0)
			)
			(min_thickness 0.25)
			(keepout
				(tracks allowed)
				(vias not_allowed)
				(pads allowed)
				(copperpour not_allowed)
				(footprints allowed)
			)
			(placement
				(enabled no)
				(sheetname "")
			)
			(fill
				(thermal_gap 0.5)
				(thermal_bridge_width 0.5)
				(island_removal_mode 0)
			)
			(polygon
				(pts
					(xy 84.7852 -73.2028) (xy 85.3948 -73.2028) (xy 85.3948 -73.3552) (xy 84.7852 -73.3552)
				)
			)
		)
		(zone
			(layer "B.Cu")
			(hatch none 0.5)
			(connect_pads
				(clearance 0)
			)
			(min_thickness 0.25)
			(keepout
				(tracks not_allowed)
				(vias allowed)
				(pads allowed)
				(copperpour not_allowed)
				(footprints allowed)
			)
			(placement
				(enabled no)
				(sheetname "")
			)
			(fill
				(thermal_gap 0.5)
				(thermal_bridge_width 0.5)
				(island_removal_mode 0)
			)
			(polygon
				(pts
					(xy 84.7852 -73.2028) (xy 85.3948 -73.2028) (xy 85.3948 -73.3552) (xy 84.7852 -73.3552)
				)
			)
		)
	)
)
